(kicad_pcb
	(version 20260206)
	(generator "pcbnew")
	(generator_version "10.0")
	(general
		(thickness 1.21888)
		(legacy_teardrops no)
	)
	(paper "A4")
	(title_block
		(title "timecard-v9 — TimeCard-DC-V9_EXP.PcbDoc")
		(comment 1 "Time Appliance Project (Time Card) / footprints 344-353 of 402")
	)
	(layers
		(0 "F.Cu" signal "TOP")
		(4 "In1.Cu" signal "SGND")
		(6 "In2.Cu" signal "IN1")
		(8 "In3.Cu" signal "IN2")
		(10 "In4.Cu" signal "SGND1")
		(2 "B.Cu" signal "BOTTOM")
		(9 "F.Adhes" user "F.Adhesive")
		(11 "B.Adhes" user "B.Adhesive")
		(13 "F.Paste" user "Top Paste")
		(15 "B.Paste" user "Bottom Paste")
		(5 "F.SilkS" user "Top Overlay")
		(7 "B.SilkS" user "Bottom Overlay")
		(1 "F.Mask" user "Top Solder")
		(3 "B.Mask" user "Bottom Solder")
		(17 "Dwgs.User" user "User.Drawings")
		(19 "Cmts.User" user "User.Comments")
		(21 "Eco1.User" user "User.Eco1")
		(23 "Eco2.User" user "User.Eco2")
		(25 "Edge.Cuts" user)
		(27 "Margin" user)
		(31 "F.CrtYd" user "Top Courtyard")
		(29 "B.CrtYd" user "Bottom Courtyard")
		(35 "F.Fab" user "Top Component Center")
		(33 "B.Fab" user "Bottom Component Center")
	)
	(footprint "Vault:FP-C1005-050-0_05-IPC_A"
		(layer "B.Cu")
		(at 111.0216 80.9162 -90)
		(property "Reference" "C9"
			(at -0.7 1.106655 90)
			(unlocked yes)
			(layer "B.SilkS")
			(effects
				(font
					(size 0.762 0.762)
					(thickness 0.2286)
				)
				(justify left bottom mirror)
			)
		)
		(property "Value" "2.2uF_16V_0402"
			(at 5.939845 -3.6529 0)
			(unlocked yes)
			(layer "B.SilkS")
			(hide yes)
			(effects
				(font
					(size 0.762 0.762)
					(thickness 0.2286)
				)
				(justify left bottom mirror)
			)
		)
		(sheetname "05-GPS_IMU_SENSORS")
		(sheetfile "05-GPS_IMU_SENSORS.kicad_sch")
		(duplicate_pad_numbers_are_jumpers no)
		(fp_line
			(start 0.83624 0.73624)
			(end -0.83624 0.73624)
			(stroke
				(width 0.2)
				(type solid)
			)
			(layer "B.SilkS")
		)
		(fp_line
			(start 0.83624 -0.73624)
			(end -0.83624 -0.73624)
			(stroke
				(width 0.2)
				(type solid)
			)
			(layer "B.SilkS")
		)
		(fp_line
			(start -1.03624 0.53624)
			(end -1.03624 -0.53624)
			(stroke
				(width 0.2)
				(type solid)
			)
			(layer "B.CrtYd")
		)
		(fp_line
			(start 1.03623 0.53624)
			(end -1.03624 0.53624)
			(stroke
				(width 0.2)
				(type solid)
			)
			(layer "B.CrtYd")
		)
		(fp_line
			(start 1.03623 0.53624)
			(end 1.03623 -0.53624)
			(stroke
				(width 0.2)
				(type solid)
			)
			(layer "B.CrtYd")
		)
		(fp_line
			(start 1.03623 -0.53624)
			(end -1.03624 -0.53624)
			(stroke
				(width 0.2)
				(type solid)
			)
			(layer "B.CrtYd")
		)
		(fp_line
			(start -1.03624 0.53624)
			(end -1.03624 -0.53624)
			(stroke
				(width 0.2)
				(type solid)
			)
			(layer "B.Fab")
		)
		(fp_line
			(start 1.03623 0.53624)
			(end -1.03624 0.53624)
			(stroke
				(width 0.2)
				(type solid)
			)
			(layer "B.Fab")
		)
		(fp_line
			(start 1.03623 0.53624)
			(end 1.03623 -0.53624)
			(stroke
				(width 0.2)
				(type solid)
			)
			(layer "B.Fab")
		)
		(fp_line
			(start 0 0.5)
			(end 0 -0.5)
			(stroke
				(width 0.1)
				(type solid)
			)
			(layer "B.Fab")
		)
		(fp_line
			(start 0.5 0)
			(end -0.5 0)
			(stroke
				(width 0.1)
				(type solid)
			)
			(layer "B.Fab")
		)
		(fp_line
			(start 1.03623 -0.53624)
			(end -1.03624 -0.53624)
			(stroke
				(width 0.2)
				(type solid)
			)
			(layer "B.Fab")
		)
		(fp_text user "${REFERENCE}"
			(at -0.00001 -0.09601 90)
			(unlocked yes)
			(layer "B.Fab")
			(effects
				(font
					(face "Arial")
					(size 0.63 0.63)
					(thickness 0.1)
				)
				(justify left bottom mirror)
			)
		)
		(pad "1" smd rect
			(at -0.46658 0 270)
			(size 0.73933 0.67248)
			(layers "B.Cu" "B.Mask" "B.Paste")
			(net "BNO_P3V3")
			(solder_mask_margin 0)
			(solder_paste_margin 0)
		)
		(pad "2" smd rect
			(at 0.46657 0 270)
			(size 0.73933 0.67248)
			(layers "B.Cu" "B.Mask" "B.Paste")
			(net "GND")
			(solder_mask_margin 0)
			(solder_paste_margin 0)
		)
	)
	(footprint "Vault:CAPC1005X56X25NL10T15"
		(layer "B.Cu")
		(at 116.04815 86.2424 90)
		(property "Reference" "C84"
			(at 0.09563 1.073079 270)
			(unlocked yes)
			(layer "B.SilkS")
			(effects
				(font
					(size 0.762 0.762)
					(thickness 0.2286)
				)
				(justify mirror)
			)
		)
		(property "Value" "0.1uF_25V_0402"
			(at -2.592551 -7.071595 0)
			(unlocked yes)
			(layer "B.SilkS")
			(hide yes)
			(effects
				(font
					(size 0.762 0.762)
					(thickness 0.2286)
				)
				(justify mirror)
			)
		)
		(sheetname "05-GPS_IMU_SENSORS")
		(sheetfile "05-GPS_IMU_SENSORS.kicad_sch")
		(duplicate_pad_numbers_are_jumpers no)
		(pad "1" smd rect
			(at -0.43999 0)
			(size 0.64 0.68)
			(layers "B.Cu" "B.Mask" "B.Paste")
			(net "GND")
		)
		(pad "2" smd rect
			(at 0.44001 0)
			(size 0.64 0.68)
			(layers "B.Cu" "B.Mask" "B.Paste")
			(net "BNO_P3V3")
		)
	)
	(footprint "Vault:RESC1005X40X25NL10T10"
		(layer "B.Cu")
		(at 187.1466 92.2162 -90)
		(property "Reference" "R129"
			(at -0.7032 1.226931 270)
			(unlocked yes)
			(layer "B.SilkS")
			(effects
				(font
					(size 0.762 0.762)
					(thickness 0.2032)
				)
				(justify mirror)
			)
		)
		(property "Value" "20K_1%_0402"
			(at -2.579871 -9.560015 180)
			(unlocked yes)
			(layer "B.SilkS")
			(hide yes)
			(effects
				(font
					(size 0.762 0.762)
					(thickness 0.2032)
				)
				(justify mirror)
			)
		)
		(sheetname "03-POWER")
		(sheetfile "03-POWER.kicad_sch")
		(duplicate_pad_numbers_are_jumpers no)
		(pad "1" smd rect
			(at -0.425 0 180)
			(size 0.6 0.65)
			(layers "B.Cu" "B.Mask" "B.Paste")
			(net "+12V")
		)
		(pad "2" smd rect
			(at 0.425 0 180)
			(size 0.6 0.65)
			(layers "B.Cu" "B.Mask" "B.Paste")
			(net "NetR129_2")
		)
	)
	(footprint "Vault:RESC1005X40X25ML10T10"
		(layer "B.Cu")
		(at 86.9716 62.0662)
		(property "Reference" "R26"
			(at -0.1786 -1.323079 0)
			(unlocked yes)
			(layer "B.SilkS")
			(effects
				(font
					(size 0.762 0.762)
					(thickness 0.2286)
				)
				(justify mirror)
			)
		)
		(property "Value" "1.2K_0.5%_0402"
			(at -3.087871 -2.374035 270)
			(unlocked yes)
			(layer "B.SilkS")
			(hide yes)
			(effects
				(font
					(size 0.762 0.762)
					(thickness 0.2286)
				)
				(justify mirror)
			)
		)
		(sheetname "03-POWER")
		(sheetfile "03-POWER.kicad_sch")
		(duplicate_pad_numbers_are_jumpers no)
		(pad "1" smd rect
			(at -0.475 0 270)
			(size 0.7 0.75)
			(layers "B.Cu" "B.Mask" "B.Paste")
			(net "NetR26_1")
		)
		(pad "2" smd rect
			(at 0.475 0 270)
			(size 0.7 0.75)
			(layers "B.Cu" "B.Mask" "B.Paste")
			(net "NetR26_2")
		)
	)
	(footprint "Vault:RESC1005X40X25NL10T10"
		(layer "B.Cu")
		(at 125.5216 64.96075 90)
		(property "Reference" "R132"
			(at -0.25865 -1.473069 90)
			(unlocked yes)
			(layer "B.SilkS")
			(effects
				(font
					(size 0.762 0.762)
					(thickness 0.2032)
				)
				(justify mirror)
			)
		)
		(property "Value" "4.7K_1%_0402"
			(at -2.732271 -8.747465 0)
			(unlocked yes)
			(layer "B.SilkS")
			(hide yes)
			(effects
				(font
					(size 0.762 0.762)
					(thickness 0.2032)
				)
				(justify mirror)
			)
		)
		(sheetname "10-M2_GPS")
		(sheetfile "10-M2_GPS.kicad_sch")
		(duplicate_pad_numbers_are_jumpers no)
		(pad "1" smd rect
			(at -0.425 0)
			(size 0.6 0.65)
			(layers "B.Cu" "B.Mask" "B.Paste")
			(net "GPS1_PIN13")
		)
		(pad "2" smd rect
			(at 0.425 0)
			(size 0.6 0.65)
			(layers "B.Cu" "B.Mask" "B.Paste")
			(net "+3.3V")
		)
	)
	(footprint "Vault:FP-MK212BG-MFG"
		(layer "B.Cu")
		(at 109.87414 66.7286 -90)
		(property "Reference" "C41"
			(at -0.267115 1.591871 270)
			(unlocked yes)
			(layer "B.SilkS")
			(effects
				(font
					(size 0.762 0.762)
					(thickness 0.2286)
				)
				(justify mirror)
			)
		)
		(property "Value" "10uF"
			(at 1.45964 -2.478281 90)
			(unlocked yes)
			(layer "B.SilkS")
			(hide yes)
			(effects
				(font
					(size 0.762 0.762)
					(thickness 0.2286)
				)
				(justify mirror)
			)
		)
		(sheetname "05-GPS_IMU_SENSORS")
		(sheetfile "05-GPS_IMU_SENSORS.kicad_sch")
		(duplicate_pad_numbers_are_jumpers no)
		(fp_line
			(start 0.125 0.72499)
			(end -0.125 0.72499)
			(stroke
				(width 0.2)
				(type solid)
			)
			(layer "B.SilkS")
		)
		(fp_line
			(start 0.125 -0.725)
			(end -0.125 -0.725)
			(stroke
				(width 0.2)
				(type solid)
			)
			(layer "B.SilkS")
		)
		(fp_line
			(start -1.6 0.82499)
			(end -1.6 -0.825)
			(stroke
				(width 0.2)
				(type solid)
			)
			(layer "B.CrtYd")
		)
		(fp_line
			(start 1.6 0.82499)
			(end -1.6 0.82499)
			(stroke
				(width 0.2)
				(type solid)
			)
			(layer "B.CrtYd")
		)
		(fp_line
			(start 1.6 0.82499)
			(end 1.6 -0.825)
			(stroke
				(width 0.2)
				(type solid)
			)
			(layer "B.CrtYd")
		)
		(fp_line
			(start 1.6 -0.825)
			(end -1.6 -0.825)
			(stroke
				(width 0.2)
				(type solid)
			)
			(layer "B.CrtYd")
		)
		(fp_line
			(start -1.6 0.82499)
			(end -1.6 -0.825)
			(stroke
				(width 0.2)
				(type solid)
			)
			(layer "B.Fab")
		)
		(fp_line
			(start 1.6 0.82499)
			(end -1.6 0.82499)
			(stroke
				(width 0.2)
				(type solid)
			)
			(layer "B.Fab")
		)
		(fp_line
			(start 1.6 0.82499)
			(end 1.6 -0.825)
			(stroke
				(width 0.2)
				(type solid)
			)
			(layer "B.Fab")
		)
		(fp_line
			(start 0 0.49999)
			(end 0 -0.5)
			(stroke
				(width 0.1)
				(type solid)
			)
			(layer "B.Fab")
		)
		(fp_line
			(start 0.5 0)
			(end -0.5 0)
			(stroke
				(width 0.1)
				(type solid)
			)
			(layer "B.Fab")
		)
		(fp_line
			(start 1.6 -0.825)
			(end -1.6 -0.825)
			(stroke
				(width 0.2)
				(type solid)
			)
			(layer "B.Fab")
		)
		(fp_text user "${REFERENCE}"
			(at -0.00001 -0.09602 90)
			(unlocked yes)
			(layer "B.Fab")
			(effects
				(font
					(face "Arial")
					(size 0.63 0.63)
					(thickness 0.1)
				)
				(justify left bottom mirror)
			)
		)
		(pad "1" smd rect
			(at -1 0 270)
			(size 1 1.25)
			(layers "B.Cu" "B.Mask" "B.Paste")
			(net "+3.3V")
			(solder_mask_margin 0)
			(solder_paste_margin 0)
		)
		(pad "2" smd rect
			(at 1 0 270)
			(size 1 1.25)
			(layers "B.Cu" "B.Mask" "B.Paste")
			(net "GND")
			(solder_mask_margin 0)
			(solder_paste_margin 0)
		)
	)
	(footprint "Vault:FP-MK212BG-MFG"
		(layer "B.Cu")
		(at 103.9741 74.05812)
		(property "Reference" "C42"
			(at 0.2761 1.531149 180)
			(unlocked yes)
			(layer "B.SilkS")
			(effects
				(font
					(size 0.762 0.762)
					(thickness 0.2286)
				)
				(justify mirror)
			)
		)
		(property "Value" "10uF"
			(at -3.240271 -2.22164 270)
			(unlocked yes)
			(layer "B.SilkS")
			(hide yes)
			(effects
				(font
					(size 0.762 0.762)
					(thickness 0.2286)
				)
				(justify mirror)
			)
		)
		(sheetname "05-GPS_IMU_SENSORS")
		(sheetfile "05-GPS_IMU_SENSORS.kicad_sch")
		(duplicate_pad_numbers_are_jumpers no)
		(fp_line
			(start -0.125 -0.725)
			(end 0.125 -0.725)
			(stroke
				(width 0.2)
				(type solid)
			)
			(layer "B.SilkS")
		)
		(fp_line
			(start -0.125 0.725)
			(end 0.125 0.725)
			(stroke
				(width 0.2)
				(type solid)
			)
			(layer "B.SilkS")
		)
		(fp_line
			(start -1.6 -0.825)
			(end 1.6 -0.825)
			(stroke
				(width 0.2)
				(type solid)
			)
			(layer "B.CrtYd")
		)
		(fp_line
			(start -1.6 0.825)
			(end -1.6 -0.825)
			(stroke
				(width 0.2)
				(type solid)
			)
			(layer "B.CrtYd")
		)
		(fp_line
			(start -1.6 0.825)
			(end 1.6 0.825)
			(stroke
				(width 0.2)
				(type solid)
			)
			(layer "B.CrtYd")
		)
		(fp_line
			(start 1.6 0.825)
			(end 1.6 -0.825)
			(stroke
				(width 0.2)
				(type solid)
			)
			(layer "B.CrtYd")
		)
		(fp_line
			(start -1.6 -0.825)
			(end 1.6 -0.825)
			(stroke
				(width 0.2)
				(type solid)
			)
			(layer "B.Fab")
		)
		(fp_line
			(start -1.6 0.825)
			(end -1.6 -0.825)
			(stroke
				(width 0.2)
				(type solid)
			)
			(layer "B.Fab")
		)
		(fp_line
			(start -1.6 0.825)
			(end 1.6 0.825)
			(stroke
				(width 0.2)
				(type solid)
			)
			(layer "B.Fab")
		)
		(fp_line
			(start -0.5 0)
			(end 0.5 0)
			(stroke
				(width 0.1)
				(type solid)
			)
			(layer "B.Fab")
		)
		(fp_line
			(start 0 0.5)
			(end 0 -0.5)
			(stroke
				(width 0.1)
				(type solid)
			)
			(layer "B.Fab")
		)
		(fp_line
			(start 1.6 0.825)
			(end 1.6 -0.825)
			(stroke
				(width 0.2)
				(type solid)
			)
			(layer "B.Fab")
		)
		(fp_text user "${REFERENCE}"
			(at -0.00001 -0.09602 180)
			(unlocked yes)
			(layer "B.Fab")
			(effects
				(font
					(face "Arial")
					(size 0.63 0.63)
					(thickness 0.1)
				)
				(justify left bottom mirror)
			)
		)
		(pad "1" smd rect
			(at -1 0)
			(size 1 1.25)
			(layers "B.Cu" "B.Mask" "B.Paste")
			(net "+5.0V")
			(solder_mask_margin 0)
			(solder_paste_margin 0)
		)
		(pad "2" smd rect
			(at 1 0)
			(size 1 1.25)
			(layers "B.Cu" "B.Mask" "B.Paste")
			(net "GND")
			(solder_mask_margin 0)
			(solder_paste_margin 0)
		)
	)
	(footprint "Vault:CAPC1608X87X45ML20T05"
		(layer "B.Cu")
		(at 109.4216 75.5162)
		(property "Reference" "C59"
			(at -0.71236 0.906655 180)
			(unlocked yes)
			(layer "B.SilkS")
			(effects
				(font
					(size 0.762 0.762)
					(thickness 0.2286)
				)
				(justify left bottom mirror)
			)
		)
		(property "Value" "0.1uF"
			(at 0.2921 3.382645 0)
			(unlocked yes)
			(layer "B.SilkS")
			(hide yes)
			(effects
				(font
					(size 0.762 0.762)
					(thickness 0.2286)
				)
				(justify left bottom mirror)
			)
		)
		(sheetname "05-GPS_IMU_SENSORS")
		(sheetfile "05-GPS_IMU_SENSORS.kicad_sch")
		(duplicate_pad_numbers_are_jumpers no)
		(pad "1" smd rect
			(at -0.7 0 270)
			(size 1.1 1.05)
			(layers "B.Cu" "B.Mask" "B.Paste")
			(net "GND")
		)
		(pad "2" smd rect
			(at 0.7 0 270)
			(size 1.1 1.05)
			(layers "B.Cu" "B.Mask" "B.Paste")
			(net "+3.3V")
		)
	)
	(footprint "Vault:FP-0402-L_1_0_0_05-W_0_5-IPC_A"
		(layer "B.Cu")
		(at 96.4216 74.7162)
		(property "Reference" "C17"
			(at 0.8 -1.106655 0)
			(unlocked yes)
			(layer "B.SilkS")
			(effects
				(font
					(size 0.762 0.762)
					(thickness 0.2286)
				)
				(justify left bottom mirror)
			)
		)
		(property "Value" "1uF_16V_0402"
			(at -14.9272 10.507645 0)
			(unlocked yes)
			(layer "B.SilkS")
			(hide yes)
			(effects
				(font
					(size 0.762 0.762)
					(thickness 0.2286)
				)
				(justify left bottom mirror)
			)
		)
		(sheetname "03-POWER")
		(sheetfile "03-POWER.kicad_sch")
		(duplicate_pad_numbers_are_jumpers no)
		(fp_line
			(start -0.83624 -0.73624)
			(end 0.83624 -0.73624)
			(stroke
				(width 0.2)
				(type solid)
			)
			(layer "B.SilkS")
		)
		(fp_line
			(start -0.83624 0.73624)
			(end 0.83624 0.73624)
			(stroke
				(width 0.2)
				(type solid)
			)
			(layer "B.SilkS")
		)
		(fp_line
			(start -1.03624 -0.53624)
			(end 1.03624 -0.53624)
			(stroke
				(width 0.2)
				(type solid)
			)
			(layer "B.CrtYd")
		)
		(fp_line
			(start -1.03624 0.53624)
			(end -1.03624 -0.53624)
			(stroke
				(width 0.2)
				(type solid)
			)
			(layer "B.CrtYd")
		)
		(fp_line
			(start -1.03624 0.53624)
			(end 1.03624 0.53624)
			(stroke
				(width 0.2)
				(type solid)
			)
			(layer "B.CrtYd")
		)
		(fp_line
			(start 1.03624 0.53624)
			(end 1.03624 -0.53624)
			(stroke
				(width 0.2)
				(type solid)
			)
			(layer "B.CrtYd")
		)
		(fp_line
			(start -1.03624 -0.53624)
			(end 1.03624 -0.53624)
			(stroke
				(width 0.2)
				(type solid)
			)
			(layer "B.Fab")
		)
		(fp_line
			(start -1.03624 0.53624)
			(end -1.03624 -0.53624)
			(stroke
				(width 0.2)
				(type solid)
			)
			(layer "B.Fab")
		)
		(fp_line
			(start -1.03624 0.53624)
			(end 1.03624 0.53624)
			(stroke
				(width 0.2)
				(type solid)
			)
			(layer "B.Fab")
		)
		(fp_line
			(start -0.5 0)
			(end 0.5 0)
			(stroke
				(width 0.1)
				(type solid)
			)
			(layer "B.Fab")
		)
		(fp_line
			(start 0 0.5)
			(end 0 -0.5)
			(stroke
				(width 0.1)
				(type solid)
			)
			(layer "B.Fab")
		)
		(fp_line
			(start 1.03624 0.53624)
			(end 1.03624 -0.53624)
			(stroke
				(width 0.2)
				(type solid)
			)
			(layer "B.Fab")
		)
		(fp_text user "${REFERENCE}"
			(at -0.00002 -0.09602 180)
			(unlocked yes)
			(layer "B.Fab")
			(effects
				(font
					(face "Arial")
					(size 0.63 0.63)
					(thickness 0.1)
				)
				(justify left bottom mirror)
			)
		)
		(pad "1" smd rect
			(at -0.47856 0)
			(size 0.71535 0.67248)
			(layers "B.Cu" "B.Mask" "B.Paste")
			(net "+5.0V")
			(solder_mask_margin 0)
			(solder_paste_margin 0)
		)
		(pad "2" smd rect
			(at 0.47856 0)
			(size 0.71535 0.67248)
			(layers "B.Cu" "B.Mask" "B.Paste")
			(net "GND")
			(solder_mask_margin 0)
			(solder_paste_margin 0)
		)
	)
	(footprint "Vault:RESC1005X40X25NL10T10"
		(layer "B.Cu")
		(at 128.2216 63.82816 90)
		(property "Reference" "R134"
			(at 2.23367 0.104461 90)
			(unlocked yes)
			(layer "B.SilkS")
			(effects
				(font
					(size 0.762 0.762)
					(thickness 0.2032)
				)
				(justify mirror)
			)
		)
		(property "Value" "4.7K_1%_0402"
			(at -2.732271 -8.747465 0)
			(unlocked yes)
			(layer "B.SilkS")
			(hide yes)
			(effects
				(font
					(size 0.762 0.762)
					(thickness 0.2032)
				)
				(justify mirror)
			)
		)
		(sheetname "10-M2_GPS")
		(sheetfile "10-M2_GPS.kicad_sch")
		(duplicate_pad_numbers_are_jumpers no)
		(pad "1" smd rect
			(at -0.425 0)
			(size 0.6 0.65)
			(layers "B.Cu" "B.Mask" "B.Paste")
			(net "GPS1_PIN15")
		)
		(pad "2" smd rect
			(at 0.425 0)
			(size 0.6 0.65)
			(layers "B.Cu" "B.Mask" "B.Paste")
			(net "+3.3V")
		)
	)
)
